(kicad_pcb
	(version 20260206)
	(generator "pcbnew")
	(generator_version "10.0")
	(general
		(thickness 1.6)
		(legacy_teardrops no)
	)
	(paper "A4")
	(title_block
		(title "Bryce Canyon_F.DPB_16315-1-OCP.brd")
		(comment 1 "Bryce Canyon / footprints 1771-1777 of 2223")
	)
	(layers
		(0 "F.Cu" signal "TOP")
		(4 "In1.Cu" signal "L2GND")
		(6 "In2.Cu" signal "L3")
		(8 "In3.Cu" signal "L4GND")
		(10 "In4.Cu" signal "L5")
		(12 "In5.Cu" signal "L6VCC")
		(14 "In6.Cu" signal "L7VCC")
		(16 "In7.Cu" signal "L8")
		(18 "In8.Cu" signal "L9GND")
		(20 "In9.Cu" signal "L10")
		(22 "In10.Cu" signal "L11GND")
		(2 "B.Cu" signal "BOTTOM")
		(9 "F.Adhes" user "F.Adhesive")
		(11 "B.Adhes" user "B.Adhesive")
		(13 "F.Paste" user "Package Geometry/Pastemask Top")
		(15 "B.Paste" user "Package Geometry/Pastemask Bottom")
		(5 "F.SilkS" user "Ref Des/Silkscreen Top")
		(7 "B.SilkS" user "Ref Des/Silkscreen Bottom")
		(1 "F.Mask" user "Board Geometry/Soldermask Top")
		(3 "B.Mask" user "Board Geometry/Soldermask Bottom")
		(17 "Dwgs.User" user "User.Drawings")
		(19 "Cmts.User" user "User.Comments")
		(21 "Eco1.User" user "User.Eco1")
		(23 "Eco2.User" user "User.Eco2")
		(25 "Edge.Cuts" user "Board Geometry/Outline")
		(27 "Margin" user)
		(31 "F.CrtYd" user "Package Geometry/Place Bound Top")
		(29 "B.CrtYd" user "Package Geometry/Place Bound Bottom")
		(35 "F.Fab" user "Ref Des/Assembly Top")
		(33 "B.Fab" user "Ref Des/Assembly Bottom")
	)
	(footprint ""
		(layer "F.Cu")
		(at 466.453474 -291.124386)
		(property "Reference" "R596"
			(at 0 0 0)
			(layer "F.SilkS")
			(hide yes)
			(effects
				(font
					(size 1.27 1.27)
				)
			)
		)
		(property "Value" "4K7R2J-2-GP"
			(at 0.064008 -3.993896 0)
			(unlocked yes)
			(layer "F.Fab")
			(hide yes)
			(effects
				(font
					(size 1.016 1.016)
					(thickness 0.1524)
				)
			)
		)
		(property "Device Type" "R402H16"
			(at 0.064008 -5.517896 0)
			(unlocked yes)
			(layer "F.Fab")
			(hide yes)
			(effects
				(font
					(size 1.016 1.016)
					(thickness 0.1524)
				)
			)
		)
		(duplicate_pad_numbers_are_jumpers no)
		(fp_line
			(start -0.508 -0.9398)
			(end -0.508 0.9398)
			(stroke
				(width 0.1524)
				(type default)
			)
			(layer "F.SilkS")
		)
		(fp_line
			(start 0.508 -0.9398)
			(end -0.508 -0.9398)
			(stroke
				(width 0.1524)
				(type default)
			)
			(layer "F.SilkS")
		)
		(fp_rect
			(start -0.508 0.9398)
			(end 0.508 -0.9398)
			(stroke
				(width 0)
				(type default)
			)
			(fill no)
			(layer "F.CrtYd")
		)
		(fp_rect
			(start -0.508 0.9398)
			(end 0.508 -0.9398)
			(stroke
				(width 0)
				(type default)
			)
			(fill no)
			(layer "F.Fab")
		)
		(pad "1" smd custom
			(at 0 -0.4445)
			(size 0.1397 0.1397)
			(layers "F.Cu" "F.Mask" "F.Paste")
			(net "DRIVE_B_35_FLT_LED")
			(options
				(clearance outline)
				(anchor circle)
			)
			(primitives
				(gr_poly
					(pts
						(arc
							(start -0.1778 -0.2794)
							(mid -0.249642 -0.249642)
							(end -0.2794 -0.1778)
						)
						(arc
							(start -0.2794 0.1778)
							(mid -0.249642 0.249642)
							(end -0.1778 0.2794)
						)
						(arc
							(start 0.1778 0.2794)
							(mid 0.249642 0.249642)
							(end 0.2794 0.1778)
						)
						(arc
							(start 0.2794 -0.1778)
							(mid 0.249642 -0.249642)
							(end 0.1778 -0.2794)
						)
					)
					(width 0)
					(fill yes)
				)
			)
		)
		(pad "2" smd custom
			(at 0 0.4445)
			(size 0.1397 0.1397)
			(layers "F.Cu" "F.Mask" "F.Paste")
			(net "GND")
			(options
				(clearance outline)
				(anchor circle)
			)
			(primitives
				(gr_poly
					(pts
						(arc
							(start -0.1778 -0.2794)
							(mid -0.249642 -0.249642)
							(end -0.2794 -0.1778)
						)
						(arc
							(start -0.2794 0.1778)
							(mid -0.249642 0.249642)
							(end -0.1778 0.2794)
						)
						(arc
							(start 0.1778 0.2794)
							(mid 0.249642 0.249642)
							(end 0.2794 0.1778)
						)
						(arc
							(start 0.2794 -0.1778)
							(mid 0.249642 -0.249642)
							(end 0.1778 -0.2794)
						)
					)
					(width 0)
					(fill yes)
				)
			)
		)
	)
	(footprint ""
		(layer "F.Cu")
		(at 286.7152 -284.5308)
		(property "Reference" "R119"
			(at 0 0 0)
			(layer "F.SilkS")
			(hide yes)
			(effects
				(font
					(size 1.27 1.27)
				)
			)
		)
		(property "Value" "4K7R2F-GP"
			(at 0.064008 -3.993896 0)
			(unlocked yes)
			(layer "F.Fab")
			(hide yes)
			(effects
				(font
					(size 1.016 1.016)
					(thickness 0.1524)
				)
			)
		)
		(property "Device Type" "R402H16"
			(at 0.064008 -5.517896 0)
			(unlocked yes)
			(layer "F.Fab")
			(hide yes)
			(effects
				(font
					(size 1.016 1.016)
					(thickness 0.1524)
				)
			)
		)
		(duplicate_pad_numbers_are_jumpers no)
		(fp_line
			(start -0.508 -0.9398)
			(end -0.508 0.9398)
			(stroke
				(width 0.1524)
				(type default)
			)
			(layer "F.SilkS")
		)
		(fp_line
			(start 0.508 -0.9398)
			(end -0.508 -0.9398)
			(stroke
				(width 0.1524)
				(type default)
			)
			(layer "F.SilkS")
		)
		(fp_rect
			(start -0.508 0.9398)
			(end 0.508 -0.9398)
			(stroke
				(width 0)
				(type default)
			)
			(fill no)
			(layer "F.CrtYd")
		)
		(fp_rect
			(start -0.508 0.9398)
			(end 0.508 -0.9398)
			(stroke
				(width 0)
				(type default)
			)
			(fill no)
			(layer "F.Fab")
		)
		(pad "1" smd custom
			(at 0 -0.4445)
			(size 0.1397 0.1397)
			(layers "F.Cu" "F.Mask" "F.Paste")
			(net "P3V3_STBY_A")
			(options
				(clearance outline)
				(anchor circle)
			)
			(primitives
				(gr_poly
					(pts
						(arc
							(start -0.1778 -0.2794)
							(mid -0.249642 -0.249642)
							(end -0.2794 -0.1778)
						)
						(arc
							(start -0.2794 0.1778)
							(mid -0.249642 0.249642)
							(end -0.1778 0.2794)
						)
						(arc
							(start 0.1778 0.2794)
							(mid 0.249642 0.249642)
							(end 0.2794 0.1778)
						)
						(arc
							(start 0.2794 -0.1778)
							(mid 0.249642 -0.249642)
							(end 0.1778 -0.2794)
						)
					)
					(width 0)
					(fill yes)
				)
			)
		)
		(pad "2" smd custom
			(at 0 0.4445)
			(size 0.1397 0.1397)
			(layers "F.Cu" "F.Mask" "F.Paste")
			(net "IO_EXP2_HDD_FAULT_A0")
			(options
				(clearance outline)
				(anchor circle)
			)
			(primitives
				(gr_poly
					(pts
						(arc
							(start -0.1778 -0.2794)
							(mid -0.249642 -0.249642)
							(end -0.2794 -0.1778)
						)
						(arc
							(start -0.2794 0.1778)
							(mid -0.249642 0.249642)
							(end -0.1778 0.2794)
						)
						(arc
							(start 0.1778 0.2794)
							(mid 0.249642 0.249642)
							(end 0.2794 0.1778)
						)
						(arc
							(start 0.2794 -0.1778)
							(mid 0.249642 -0.249642)
							(end 0.1778 -0.2794)
						)
					)
					(width 0)
					(fill yes)
				)
			)
		)
	)
	(footprint ""
		(layer "F.Cu")
		(at 113.200942 -277.196804 -90)
		(property "Reference" "R216"
			(at 0 0 270)
			(layer "F.SilkS")
			(hide yes)
			(effects
				(font
					(size 1.27 1.27)
				)
			)
		)
		(property "Value" "0R2J-2-GP"
			(at 0.064008 -3.993896 270)
			(unlocked yes)
			(layer "F.Fab")
			(hide yes)
			(effects
				(font
					(size 1.016 1.016)
					(thickness 0.1524)
				)
			)
		)
		(property "Device Type" "R402H16"
			(at 0.064008 -5.517896 270)
			(unlocked yes)
			(layer "F.Fab")
			(hide yes)
			(effects
				(font
					(size 1.016 1.016)
					(thickness 0.1524)
				)
			)
		)
		(duplicate_pad_numbers_are_jumpers no)
		(fp_line
			(start -0.508 -0.9398)
			(end -0.508 0.9398)
			(stroke
				(width 0.1524)
				(type default)
			)
			(layer "F.SilkS")
		)
		(fp_line
			(start 0.508 -0.9398)
			(end -0.508 -0.9398)
			(stroke
				(width 0.1524)
				(type default)
			)
			(layer "F.SilkS")
		)
		(fp_rect
			(start -0.508 0.9398)
			(end 0.508 -0.9398)
			(stroke
				(width 0)
				(type default)
			)
			(fill no)
			(layer "F.CrtYd")
		)
		(fp_rect
			(start -0.508 0.9398)
			(end 0.508 -0.9398)
			(stroke
				(width 0)
				(type default)
			)
			(fill no)
			(layer "F.Fab")
		)
		(pad "1" smd custom
			(at 0 -0.4445 270)
			(size 0.1397 0.1397)
			(layers "F.Cu" "F.Mask" "F.Paste")
			(net "SW_HDD_G3")
			(options
				(clearance outline)
				(anchor circle)
			)
			(primitives
				(gr_poly
					(pts
						(arc
							(start -0.1778 -0.2794)
							(mid -0.249642 -0.249642)
							(end -0.2794 -0.1778)
						)
						(arc
							(start -0.2794 0.1778)
							(mid -0.249642 0.249642)
							(end -0.1778 0.2794)
						)
						(arc
							(start 0.1778 0.2794)
							(mid 0.249642 0.249642)
							(end 0.2794 0.1778)
						)
						(arc
							(start 0.2794 -0.1778)
							(mid 0.249642 -0.249642)
							(end 0.1778 -0.2794)
						)
					)
					(width 0)
					(fill yes)
				)
			)
		)
		(pad "2" smd custom
			(at 0 0.4445 270)
			(size 0.1397 0.1397)
			(layers "F.Cu" "F.Mask" "F.Paste")
			(net "SW_HDD_R3")
			(options
				(clearance outline)
				(anchor circle)
			)
			(primitives
				(gr_poly
					(pts
						(arc
							(start -0.1778 -0.2794)
							(mid -0.249642 -0.249642)
							(end -0.2794 -0.1778)
						)
						(arc
							(start -0.2794 0.1778)
							(mid -0.249642 0.249642)
							(end -0.1778 0.2794)
						)
						(arc
							(start 0.1778 0.2794)
							(mid 0.249642 0.249642)
							(end 0.2794 0.1778)
						)
						(arc
							(start 0.2794 -0.1778)
							(mid 0.249642 -0.249642)
							(end 0.1778 -0.2794)
						)
					)
					(width 0)
					(fill yes)
				)
			)
		)
	)
	(footprint ""
		(layer "F.Cu")
		(at 109.873796 -47.183294 180)
		(property "Reference" "R767"
			(at 0 0 180)
			(layer "F.SilkS")
			(hide yes)
			(effects
				(font
					(size 1.27 1.27)
				)
			)
		)
		(property "Value" "200KR2F-L-GP"
			(at 0.064008 -3.993896 180)
			(unlocked yes)
			(layer "F.Fab")
			(hide yes)
			(effects
				(font
					(size 1.016 1.016)
					(thickness 0.1524)
				)
			)
		)
		(property "Device Type" "R402H16"
			(at 0.064008 -5.517896 180)
			(unlocked yes)
			(layer "F.Fab")
			(hide yes)
			(effects
				(font
					(size 1.016 1.016)
					(thickness 0.1524)
				)
			)
		)
		(duplicate_pad_numbers_are_jumpers no)
		(fp_line
			(start 0.508 -0.9398)
			(end -0.508 -0.9398)
			(stroke
				(width 0.1524)
				(type default)
			)
			(layer "F.SilkS")
		)
		(fp_line
			(start -0.508 -0.9398)
			(end -0.508 0.9398)
			(stroke
				(width 0.1524)
				(type default)
			)
			(layer "F.SilkS")
		)
		(fp_rect
			(start -0.508 0.9398)
			(end 0.508 -0.9398)
			(stroke
				(width 0)
				(type default)
			)
			(fill no)
			(layer "F.CrtYd")
		)
		(fp_rect
			(start -0.508 0.9398)
			(end 0.508 -0.9398)
			(stroke
				(width 0)
				(type default)
			)
			(fill no)
			(layer "F.Fab")
		)
		(pad "1" smd custom
			(at 0 -0.4445 180)
			(size 0.1397 0.1397)
			(layers "F.Cu" "F.Mask" "F.Paste")
			(net "SW_HDD_R27")
			(options
				(clearance outline)
				(anchor circle)
			)
			(primitives
				(gr_poly
					(pts
						(arc
							(start -0.1778 -0.2794)
							(mid -0.249642 -0.249642)
							(end -0.2794 -0.1778)
						)
						(arc
							(start -0.2794 0.1778)
							(mid -0.249642 0.249642)
							(end -0.1778 0.2794)
						)
						(arc
							(start 0.1778 0.2794)
							(mid 0.249642 0.249642)
							(end 0.2794 0.1778)
						)
						(arc
							(start 0.2794 -0.1778)
							(mid 0.249642 -0.249642)
							(end 0.1778 -0.2794)
						)
					)
					(width 0)
					(fill yes)
				)
			)
		)
		(pad "2" smd custom
			(at 0 0.4445 180)
			(size 0.1397 0.1397)
			(layers "F.Cu" "F.Mask" "F.Paste")
			(net "SW_HDD_N27")
			(options
				(clearance outline)
				(anchor circle)
			)
			(primitives
				(gr_poly
					(pts
						(arc
							(start -0.1778 -0.2794)
							(mid -0.249642 -0.249642)
							(end -0.2794 -0.1778)
						)
						(arc
							(start -0.2794 0.1778)
							(mid -0.249642 0.249642)
							(end -0.1778 0.2794)
						)
						(arc
							(start 0.1778 0.2794)
							(mid 0.249642 0.249642)
							(end 0.2794 0.1778)
						)
						(arc
							(start 0.2794 -0.1778)
							(mid 0.249642 -0.249642)
							(end 0.1778 -0.2794)
						)
					)
					(width 0)
					(fill yes)
				)
			)
		)
	)
	(footprint ""
		(layer "F.Cu")
		(at 303.267872 -19.600672 90)
		(property "Reference" "TC1"
			(at 0 0 90)
			(layer "F.SilkS")
			(hide yes)
			(effects
				(font
					(size 1.27 1.27)
				)
			)
		)
		(property "Value" "ST100U16VDM-3-GP"
			(at 0 -9.6012 90)
			(unlocked yes)
			(layer "F.Fab")
			(hide yes)
			(effects
				(font
					(size 1.016 1.016)
					(thickness 0.1524)
				)
			)
		)
		(property "Device Type" "CT7343H79"
			(at 0 -11.1252 90)
			(unlocked yes)
			(layer "F.Fab")
			(hide yes)
			(effects
				(font
					(size 1.016 1.016)
					(thickness 0.1524)
				)
			)
		)
		(duplicate_pad_numbers_are_jumpers no)
		(fp_line
			(start 2.286 -4.8768)
			(end -2.286 -4.8768)
			(stroke
				(width 0.1524)
				(type default)
			)
			(layer "F.SilkS")
		)
		(fp_line
			(start -2.286 -4.8768)
			(end -2.286 -2.032)
			(stroke
				(width 0.1524)
				(type default)
			)
			(layer "F.SilkS")
		)
		(fp_line
			(start 2.1082 -4.699)
			(end -2.1082 -4.699)
			(stroke
				(width 0.508)
				(type default)
			)
			(layer "F.SilkS")
		)
		(fp_line
			(start 2.286 -2.032)
			(end 2.286 -4.8768)
			(stroke
				(width 0.1524)
				(type default)
			)
			(layer "F.SilkS")
		)
		(fp_line
			(start 2.286 2.032)
			(end 2.286 4.8768)
			(stroke
				(width 0.1524)
				(type default)
			)
			(layer "F.SilkS")
		)
		(fp_line
			(start 2.286 4.8768)
			(end -2.286 4.8768)
			(stroke
				(width 0.1524)
				(type default)
			)
			(layer "F.SilkS")
		)
		(fp_line
			(start -2.286 4.8768)
			(end -2.286 2.032)
			(stroke
				(width 0.1524)
				(type default)
			)
			(layer "F.SilkS")
		)
		(fp_rect
			(start -2.1463 3.6449)
			(end 2.1463 -3.6449)
			(stroke
				(width 0)
				(type default)
			)
			(fill no)
			(layer "F.CrtYd")
		)
		(fp_poly
			(pts
				(xy -2.54 4.953) (xy -2.54 4.2926) (xy -3.81 4.2926) (xy -3.81 -4.2926) (xy -2.54 -4.2926) (xy -2.54 -4.953)
				(xy 2.54 -4.953) (xy 2.54 -4.2926) (xy 3.81 -4.2926) (xy 3.81 -1.6256) (xy 2.1463 -1.6256) (xy 2.1463 -3.6449)
				(xy -2.1463 -3.6449) (xy -2.1463 3.6449) (xy 2.1463 3.6449) (xy 2.1463 -1.6129) (xy 3.81 -1.6129)
				(xy 3.81 4.2926) (xy 2.54 4.2926) (xy 2.54 4.953)
			)
			(stroke
				(width 0)
				(type default)
			)
			(fill no)
			(layer "F.CrtYd")
		)
		(fp_rect
			(start 2.54 4.2926)
			(end 3.81 -4.2926)
			(stroke
				(width 0)
				(type default)
			)
			(fill no)
			(layer "F.Fab")
		)
		(fp_rect
			(start -3.81 4.2926)
			(end -2.54 -4.2926)
			(stroke
				(width 0)
				(type default)
			)
			(fill no)
			(layer "F.Fab")
		)
		(fp_rect
			(start -2.54 4.953)
			(end 2.54 -4.953)
			(stroke
				(width 0)
				(type default)
			)
			(fill no)
			(layer "F.Fab")
		)
		(pad "1" smd rect
			(at 0 -3.1496 90)
			(size 2.413 2.286)
			(layers "F.Cu" "F.Mask" "F.Paste")
			(net "P12V_B_COMP")
		)
		(pad "2" smd rect
			(at 0 3.1496 90)
			(size 2.413 2.286)
			(layers "F.Cu" "F.Mask" "F.Paste")
			(net "GND")
		)
		(zone
			(layer "F.Cu")
			(hatch none 0.5)
			(connect_pads
				(clearance 0)
			)
			(min_thickness 0.25)
			(keepout
				(tracks allowed)
				(vias not_allowed)
				(pads allowed)
				(copperpour not_allowed)
				(footprints allowed)
			)
			(placement
				(enabled no)
				(sheetname "")
			)
			(fill
				(thermal_gap 0.5)
				(thermal_bridge_width 0.5)
				(island_removal_mode 0)
			)
			(polygon
				(pts
					(xy 301.578772 -21.111972) (xy 298.670472 -21.111972) (xy 298.670472 -18.089372) (xy 301.566072 -18.089372)
					(xy 301.896272 -18.089372) (xy 301.896272 -21.111972)
				)
			)
		)
		(zone
			(layer "F.Cu")
			(hatch none 0.5)
			(connect_pads
				(clearance 0)
			)
			(min_thickness 0.25)
			(keepout
				(tracks allowed)
				(vias not_allowed)
				(pads allowed)
				(copperpour not_allowed)
				(footprints allowed)
			)
			(placement
				(enabled no)
				(sheetname "")
			)
			(fill
				(thermal_gap 0.5)
				(thermal_bridge_width 0.5)
				(island_removal_mode 0)
			)
			(polygon
				(pts
					(xy 307.865272 -18.089372) (xy 307.865272 -21.111972) (xy 304.969672 -21.111972) (xy 304.639472 -21.111972)
					(xy 304.639472 -18.089372) (xy 304.969672 -18.089372)
				)
			)
		)
	)
	(footprint ""
		(layer "F.Cu")
		(at 361.6198 -140.6144 90)
		(property "Reference" "R1106"
			(at 0 0 90)
			(layer "F.SilkS")
			(hide yes)
			(effects
				(font
					(size 1.27 1.27)
				)
			)
		)
		(property "Value" "10R2F-L-GP"
			(at 0.064008 -3.993896 90)
			(unlocked yes)
			(layer "F.Fab")
			(hide yes)
			(effects
				(font
					(size 1.016 1.016)
					(thickness 0.1524)
				)
			)
		)
		(property "Device Type" "R402H14"
			(at 0.064008 -5.517896 90)
			(unlocked yes)
			(layer "F.Fab")
			(hide yes)
			(effects
				(font
					(size 1.016 1.016)
					(thickness 0.1524)
				)
			)
		)
		(duplicate_pad_numbers_are_jumpers no)
		(fp_line
			(start 0.508 -0.9398)
			(end -0.508 -0.9398)
			(stroke
				(width 0.1524)
				(type default)
			)
			(layer "F.SilkS")
		)
		(fp_line
			(start -0.508 -0.9398)
			(end -0.508 0.9398)
			(stroke
				(width 0.1524)
				(type default)
			)
			(layer "F.SilkS")
		)
		(fp_rect
			(start -0.508 0.9398)
			(end 0.508 -0.9398)
			(stroke
				(width 0)
				(type default)
			)
			(fill no)
			(layer "F.CrtYd")
		)
		(fp_rect
			(start -0.508 0.9398)
			(end 0.508 -0.9398)
			(stroke
				(width 0)
				(type default)
			)
			(fill no)
			(layer "F.Fab")
		)
		(pad "1" smd custom
			(at 0 -0.4445 90)
			(size 0.1397 0.1397)
			(layers "F.Cu" "F.Mask" "F.Paste")
			(net "MB1_CM_SENSE_R1_N")
			(options
				(clearance outline)
				(anchor circle)
			)
			(primitives
				(gr_poly
					(pts
						(arc
							(start -0.1778 -0.2794)
							(mid -0.249642 -0.249642)
							(end -0.2794 -0.1778)
						)
						(arc
							(start -0.2794 0.1778)
							(mid -0.249642 0.249642)
							(end -0.1778 0.2794)
						)
						(arc
							(start 0.1778 0.2794)
							(mid 0.249642 0.249642)
							(end 0.2794 0.1778)
						)
						(arc
							(start 0.2794 -0.1778)
							(mid 0.249642 -0.249642)
							(end 0.1778 -0.2794)
						)
					)
					(width 0)
					(fill yes)
				)
			)
		)
		(pad "2" smd custom
			(at 0 0.4445 90)
			(size 0.1397 0.1397)
			(layers "F.Cu" "F.Mask" "F.Paste")
			(net "MB1_HS_SENSE_N")
			(options
				(clearance outline)
				(anchor circle)
			)
			(primitives
				(gr_poly
					(pts
						(arc
							(start -0.1778 -0.2794)
							(mid -0.249642 -0.249642)
							(end -0.2794 -0.1778)
						)
						(arc
							(start -0.2794 0.1778)
							(mid -0.249642 0.249642)
							(end -0.1778 0.2794)
						)
						(arc
							(start 0.1778 0.2794)
							(mid 0.249642 0.249642)
							(end 0.2794 0.1778)
						)
						(arc
							(start 0.2794 -0.1778)
							(mid 0.249642 -0.249642)
							(end 0.1778 -0.2794)
						)
					)
					(width 0)
					(fill yes)
				)
			)
		)
	)
	(footprint ""
		(layer "F.Cu")
		(at 87.036148 -186.287918)
		(property "Reference" "C227"
			(at 0 0 0)
			(layer "F.SilkS")
			(hide yes)
			(effects
				(font
					(size 1.27 1.27)
				)
			)
		)
		(property "Value" "SC4D7U25V5KX-1-GP"
			(at -0.0762 -6.1214 0)
			(unlocked yes)
			(layer "F.Fab")
			(hide yes)
			(effects
				(font
					(size 1.016 1.016)
					(thickness 0.1524)
				)
			)
		)
		(property "Device Type" "C805H58"
			(at -0.0762 -8.1534 0)
			(unlocked yes)
			(layer "F.Fab")
			(hide yes)
			(effects
				(font
					(size 1.016 1.016)
					(thickness 0.1524)
				)
			)
		)
		(duplicate_pad_numbers_are_jumpers no)
		(fp_line
			(start 0.635 0)
			(end -0.635 0)
			(stroke
				(width 0.508)
				(type default)
			)
			(layer "F.SilkS")
		)
		(fp_rect
			(start -0.9652 1.778)
			(end 0.9652 -1.778)
			(stroke
				(width 0)
				(type default)
			)
			(fill no)
			(layer "F.CrtYd")
		)
		(fp_poly
			(pts
				(xy -0.9652 -1.778) (xy 0.9652 -1.778) (xy 0.9652 1.778) (xy -0.9652 1.778)
			)
			(stroke
				(width 0)
				(type default)
			)
			(fill no)
			(layer "F.Fab")
		)
		(pad "1" smd rect
			(at 0 -0.9652)
			(size 1.397 1.143)
			(layers "F.Cu" "F.Mask" "F.Paste")
			(net "P12V_HDD14")
		)
		(pad "2" smd rect
			(at 0 0.9652)
			(size 1.397 1.143)
			(layers "F.Cu" "F.Mask" "F.Paste")
			(net "GND")
		)
	)
)
